#ISCELL
  logical_power design_note *
  *
#ISCELL
  mstr_misc dns *
  *
#ISCELL
  pure_quanta quanta_title_block_c *
  *
#ISCELL
  logical_power universal_gnd *
  page227_i1
#ISCELL
  standard offpage *
  page227_i10
#CELL
  pure_quanta q_res *
  page227_i100
#CELL
  pure_quanta q_res *
  page227_i101
#CELL
  pure_quanta q_res *
  page227_i102
#ISCELL
  standard offpage *
  page227_i103
#ISCELL
  standard offpage *
  page227_i104
#ISCELL
  standard offpage *
  page227_i105
#ISCELL
  standard offpage *
  page227_i106
#ISCELL
  standard offpage *
  page227_i107
#ISCELL
  standard offpage *
  page227_i108
#ISCELL
  standard offpage *
  page227_i109
#ISCELL
  standard offpage *
  page227_i11
#ISCELL
  standard offpage *
  page227_i110
#ISCELL
  standard offpage *
  page227_i111
#ISCELL
  standard offpage *
  page227_i112
#ISCELL
  standard offpage *
  page227_i113
#ISCELL
  standard offpage *
  page227_i114
#ISCELL
  standard offpage *
  page227_i115
#ISCELL
  standard offpage *
  page227_i116
#ISCELL
  standard offpage *
  page227_i117
#ISCELL
  standard offpage *
  page227_i118
#ISCELL
  standard offpage *
  page227_i119
#ISCELL
  standard offpage *
  page227_i12
#ISCELL
  standard offpage *
  page227_i120
#ISCELL
  standard offpage *
  page227_i121
#ISCELL
  standard offpage *
  page227_i122
#ISCELL
  standard offpage *
  page227_i123
#ISCELL
  standard offpage *
  page227_i124
#ISCELL
  standard offpage *
  page227_i125
#ISCELL
  logical_power universal_power *
  page227_i126
#ISCELL
  standard offpage *
  page227_i127
#ISCELL
  standard offpage *
  page227_i128
#ISCELL
  standard offpage *
  page227_i129
#ISCELL
  standard offpage *
  page227_i13
#ISCELL
  standard offpage *
  page227_i130
#ISCELL
  standard offpage *
  page227_i131
#ISCELL
  standard offpage *
  page227_i132
#ISCELL
  standard offpage *
  page227_i133
#ISCELL
  standard offpage *
  page227_i134
#ISCELL
  standard offpage *
  page227_i135
#ISCELL
  standard offpage *
  page227_i136
#ISCELL
  standard offpage *
  page227_i137
#ISCELL
  standard offpage *
  page227_i138
#ISCELL
  standard offpage *
  page227_i139
#ISCELL
  standard offpage *
  page227_i14
#ISCELL
  standard offpage *
  page227_i140
#ISCELL
  standard offpage *
  page227_i141
#ISCELL
  standard offpage *
  page227_i142
#ISCELL
  standard offpage *
  page227_i143
#ISCELL
  standard offpage *
  page227_i144
#ISCELL
  standard offpage *
  page227_i145
#ISCELL
  standard offpage *
  page227_i146
#ISCELL
  standard offpage *
  page227_i147
#ISCELL
  standard offpage *
  page227_i148
#ISCELL
  standard offpage *
  page227_i149
#ISCELL
  standard offpage *
  page227_i15
#ISCELL
  standard offpage *
  page227_i150
#ISCELL
  standard offpage *
  page227_i151
#ISCELL
  standard offpage *
  page227_i152
#ISCELL
  standard offpage *
  page227_i153
#ISCELL
  standard offpage *
  page227_i154
#ISCELL
  standard offpage *
  page227_i155
#ISCELL
  standard offpage *
  page227_i156
#ISCELL
  standard offpage *
  page227_i157
#ISCELL
  standard offpage *
  page227_i158
#CELL
  pure_quanta q_res *
  page227_i159
#ISCELL
  standard offpage *
  page227_i16
#ISCELL
  logical_power universal_power *
  page227_i160
#ISCELL
  standard offpage *
  page227_i161
#ISCELL
  standard offpage *
  page227_i162
#ISCELL
  standard offpage *
  page227_i163
#CELL
  pure_quanta q_res *
  page227_i164
#ISCELL
  standard offpage *
  page227_i165
#ISCELL
  standard offpage *
  page227_i166
#CELL
  pure_quanta q_res *
  page227_i167
#ISCELL
  standard offpage *
  page227_i168
#ISCELL
  standard offpage *
  page227_i169
#ISCELL
  standard offpage *
  page227_i17
#ISCELL
  standard offpage *
  page227_i170
#ISCELL
  logical_power universal_gnd *
  page227_i171
#CELL
  pure_quanta q_res *
  page227_i172
#CELL
  pure_quanta sconn168_me1016810202011 *
  page227_i173
#CELL
  pure_quanta q_res *
  page227_i18
#CELL
  pure_quanta q_res *
  page227_i19
#CELL
  pure_quanta q_res *
  page227_i2
#CELL
  pure_quanta q_res *
  page227_i20
#CELL
  pure_quanta q_res *
  page227_i21
#CELL
  pure_quanta q_res *
  page227_i22
#CELL
  pure_quanta q_res *
  page227_i23
#CELL
  pure_quanta q_res *
  page227_i24
#CELL
  pure_quanta q_res *
  page227_i25
#CELL
  pure_quanta q_res *
  page227_i26
#CELL
  pure_quanta q_res *
  page227_i27
#CELL
  pure_quanta q_res *
  page227_i28
#ISCELL
  standard offpage *
  page227_i29
#ISCELL
  standard offpage *
  page227_i3
#ISCELL
  standard offpage *
  page227_i30
#ISCELL
  standard offpage *
  page227_i31
#ISCELL
  standard offpage *
  page227_i32
#ISCELL
  standard offpage *
  page227_i33
#ISCELL
  standard offpage *
  page227_i34
#ISCELL
  standard offpage *
  page227_i35
#ISCELL
  standard offpage *
  page227_i36
#ISCELL
  standard offpage *
  page227_i37
#ISCELL
  standard offpage *
  page227_i38
#ISCELL
  standard offpage *
  page227_i39
#ISCELL
  standard offpage *
  page227_i4
#ISCELL
  logical_power universal_gnd *
  page227_i40
#ISCELL
  logical_power universal_gnd *
  page227_i41
#ISCELL
  standard offpage *
  page227_i42
#ISCELL
  standard offpage *
  page227_i43
#ISCELL
  standard offpage *
  page227_i44
#ISCELL
  standard offpage *
  page227_i45
#ISCELL
  standard offpage *
  page227_i46
#ISCELL
  standard offpage *
  page227_i47
#CELL
  pure_quanta q_res *
  page227_i48
#CELL
  pure_quanta q_res *
  page227_i49
#ISCELL
  standard offpage *
  page227_i5
#ISCELL
  standard offpage *
  page227_i50
#ISCELL
  standard offpage *
  page227_i51
#ISCELL
  standard offpage *
  page227_i52
#ISCELL
  standard offpage *
  page227_i53
#ISCELL
  standard offpage *
  page227_i54
#ISCELL
  standard offpage *
  page227_i55
#ISCELL
  standard offpage *
  page227_i56
#CELL
  pure_quanta q_res *
  page227_i57
#CELL
  pure_quanta q_res *
  page227_i58
#ISCELL
  standard offpage *
  page227_i59
#ISCELL
  standard offpage *
  page227_i6
#ISCELL
  standard offpage *
  page227_i60
#ISCELL
  standard offpage *
  page227_i61
#ISCELL
  standard offpage *
  page227_i62
#ISCELL
  standard offpage *
  page227_i63
#ISCELL
  standard offpage *
  page227_i64
#ISCELL
  standard offpage *
  page227_i65
#ISCELL
  standard offpage *
  page227_i66
#ISCELL
  standard offpage *
  page227_i67
#ISCELL
  standard offpage *
  page227_i68
#ISCELL
  standard offpage *
  page227_i69
#ISCELL
  standard offpage *
  page227_i7
#ISCELL
  standard offpage *
  page227_i70
#ISCELL
  standard offpage *
  page227_i71
#ISCELL
  standard offpage *
  page227_i72
#ISCELL
  standard offpage *
  page227_i73
#ISCELL
  standard offpage *
  page227_i74
#ISCELL
  standard offpage *
  page227_i75
#ISCELL
  standard offpage *
  page227_i76
#ISCELL
  standard offpage *
  page227_i77
#ISCELL
  standard offpage *
  page227_i78
#ISCELL
  standard offpage *
  page227_i79
#ISCELL
  standard offpage *
  page227_i8
#ISCELL
  standard offpage *
  page227_i80
#ISCELL
  logical_power universal_gnd *
  page227_i81
#CELL
  pure_quanta q_cap *
  page227_i82
#ISCELL
  logical_power universal_power *
  page227_i83
#CELL
  pure_quanta q_res *
  page227_i84
#CELL
  pure_quanta q_res *
  page227_i85
#CELL
  pure_quanta q_res *
  page227_i86
#CELL
  pure_quanta q_res *
  page227_i87
#CELL
  pure_quanta q_res *
  page227_i88
#CELL
  pure_quanta q_res *
  page227_i89
#ISCELL
  standard offpage *
  page227_i9
#CELL
  pure_quanta q_res *
  page227_i90
#CELL
  pure_quanta q_res *
  page227_i91
#CELL
  pure_quanta q_res *
  page227_i92
#CELL
  pure_quanta q_res *
  page227_i93
#CELL
  pure_quanta q_res *
  page227_i94
#CELL
  pure_quanta q_res *
  page227_i95
#CELL
  pure_quanta q_res *
  page227_i96
#CELL
  pure_quanta q_res *
  page227_i97
#CELL
  pure_quanta q_res *
  page227_i98
#CELL
  pure_quanta q_res *
  page227_i99
